FILE_TYPE = CONNECTIVITY;
{Allegro Design Entry HDL 17.4-2019 S026 (4007227) 1/17/2022}
"PAGE_NUMBER" = 468;
0"NC";
END.
